# S9S_MB_2U (Grand Teton) — schematic netlist excerpt (pin names and nets, part order shuffled) for the footprints in the layout excerpt that follows; sources: Cadence DE-HDL packaged netlist, KiCad conversion of 03242023_DA0F0TMBIJ0_F0T_Motherboard_J_brd_V01_OCP.brd

C1019  Q_CAP  22UF 4V 20% X6S  pkg C0402  page 74 : A = PVCCIN_CPU0 ; B = GND
PC2233  Q_CAP  1UF 25V 10% EMPTY  pkg C0402  page 242 : A = P12V_SCM_VCC ; B = GND

(kicad_pcb
	(version 20260206)
	(generator "pcbnew")
	(generator_version "10.0")
	(general
		(thickness 1.6)
		(legacy_teardrops no)
	)
	(paper "A4")
	(title_block
		(title "03242023_DA0F0TMBIJ0_F0T_Motherboard_J_brd_V01_OCP.brd")
		(comment 1 "Grand Teton / footprints 202-203 of 6105")
	)
	(layers
		(0 "F.Cu" signal "TOP")
		(4 "In1.Cu" signal "GND")
		(6 "In2.Cu" signal "IN1")
		(8 "In3.Cu" signal "GND1")
		(10 "In4.Cu" signal "IN2")
		(12 "In5.Cu" signal "GND2")
		(14 "In6.Cu" signal "IN3")
		(16 "In7.Cu" signal "GND3")
		(18 "In8.Cu" signal "VCC")
		(20 "In9.Cu" signal "VCC1")
		(22 "In10.Cu" signal "GND4")
		(24 "In11.Cu" signal "IN4")
		(26 "In12.Cu" signal "GND5")
		(28 "In13.Cu" signal "IN5")
		(30 "In14.Cu" signal "GND6")
		(32 "In15.Cu" signal "IN6")
		(34 "In16.Cu" signal "GND7")
		(2 "B.Cu" signal "BOTTOM")
		(9 "F.Adhes" user "F.Adhesive")
		(11 "B.Adhes" user "B.Adhesive")
		(13 "F.Paste" user "Package Geometry/Pastemask Top")
		(15 "B.Paste" user "Package Geometry/Pastemask Bottom")
		(5 "F.SilkS" user "Ref Des/Silkscreen Top")
		(7 "B.SilkS" user "Ref Des/Silkscreen Bottom")
		(1 "F.Mask" user "Board Geometry/Soldermask Top")
		(3 "B.Mask" user "Board Geometry/Soldermask Bottom")
		(17 "Dwgs.User" user "User.Drawings")
		(19 "Cmts.User" user "User.Comments")
		(21 "Eco1.User" user "User.Eco1")
		(23 "Eco2.User" user "User.Eco2")
		(25 "Edge.Cuts" user "Board Geometry/Outline")
		(27 "Margin" user)
		(31 "F.CrtYd" user "Package Geometry/Place Bound Top")
		(29 "B.CrtYd" user "Package Geometry/Place Bound Bottom")
		(35 "F.Fab" user "Ref Des/Assembly Top")
		(33 "B.Fab" user "Ref Des/Assembly Bottom")
	)
	(footprint ""
		(layer "F.Cu")
		(at 187.892182 -28.258008 180)
		(property "Reference" "PC2233"
			(at 0 0 180)
			(layer "F.SilkS")
			(hide yes)
			(effects
				(font
					(size 1.27 1.27)
				)
			)
		)
		(property "Value" ""
			(at 0 0 180)
			(layer "F.Fab")
			(effects
				(font
					(size 1.27 1.27)
				)
			)
		)
		(duplicate_pad_numbers_are_jumpers no)
		(fp_line
			(start 0.7874 0.4064)
			(end -0.7874 0.4064)
			(stroke
				(width 0.1524)
				(type default)
			)
			(layer "F.SilkS")
		)
		(fp_line
			(start 0.7874 -0.4064)
			(end 0.7874 0.4064)
			(stroke
				(width 0.1524)
				(type default)
			)
			(layer "F.SilkS")
		)
		(fp_line
			(start -0.7874 0.4064)
			(end -0.7874 -0.4064)
			(stroke
				(width 0.1524)
				(type default)
			)
			(layer "F.SilkS")
		)
		(fp_line
			(start -0.7874 -0.4064)
			(end 0.7874 -0.4064)
			(stroke
				(width 0.1524)
				(type default)
			)
			(layer "F.SilkS")
		)
		(fp_line
			(start 0.67945 0.3048)
			(end 0.120396 0.3048)
			(stroke
				(width 0.1)
				(type default)
			)
			(layer "F.Fab")
		)
		(fp_line
			(start 0.67945 -0.3048)
			(end 0.67945 0.3048)
			(stroke
				(width 0.1)
				(type default)
			)
			(layer "F.Fab")
		)
		(fp_line
			(start 0.12065 -0.2794)
			(end 0.12065 -0.3048)
			(stroke
				(width 0.1)
				(type default)
			)
			(layer "F.Fab")
		)
		(fp_line
			(start 0.12065 -0.3048)
			(end 0.67945 -0.3048)
			(stroke
				(width 0.1)
				(type default)
			)
			(layer "F.Fab")
		)
		(fp_line
			(start 0.120396 0.3048)
			(end 0.120396 0.2794)
			(stroke
				(width 0.1)
				(type default)
			)
			(layer "F.Fab")
		)
		(fp_line
			(start 0.120396 0.2794)
			(end -0.12065 0.2794)
			(stroke
				(width 0.1)
				(type default)
			)
			(layer "F.Fab")
		)
		(fp_line
			(start -0.12065 0.3048)
			(end -0.67945 0.3048)
			(stroke
				(width 0.1)
				(type default)
			)
			(layer "F.Fab")
		)
		(fp_line
			(start -0.12065 0.2794)
			(end -0.12065 0.3048)
			(stroke
				(width 0.1)
				(type default)
			)
			(layer "F.Fab")
		)
		(fp_line
			(start -0.12065 -0.2794)
			(end 0.12065 -0.2794)
			(stroke
				(width 0.1)
				(type default)
			)
			(layer "F.Fab")
		)
		(fp_line
			(start -0.12065 -0.305054)
			(end -0.12065 -0.2794)
			(stroke
				(width 0.1)
				(type default)
			)
			(layer "F.Fab")
		)
		(fp_line
			(start -0.67945 0.3048)
			(end -0.67945 -0.305054)
			(stroke
				(width 0.1)
				(type default)
			)
			(layer "F.Fab")
		)
		(fp_line
			(start -0.67945 -0.305054)
			(end -0.12065 -0.305054)
			(stroke
				(width 0.1)
				(type default)
			)
			(layer "F.Fab")
		)
		(pad "1" smd circle
			(at -0.40005 0 180)
			(size 0 0)
			(layers "F.Cu" "F.Mask" "F.Paste")
			(net "P12V_SCM_VCC")
		)
		(pad "2" smd circle
			(at 0.40005 0 180)
			(size 0 0)
			(layers "F.Cu" "F.Mask" "F.Paste")
			(net "GND")
		)
	)
	(footprint ""
		(layer "F.Cu")
		(at 354.262944 -241.976656 -90)
		(property "Reference" "C1019"
			(at 0 0 270)
			(layer "F.SilkS")
			(hide yes)
			(effects
				(font
					(size 1.27 1.27)
				)
			)
		)
		(property "Value" ""
			(at 0 0 270)
			(layer "F.Fab")
			(effects
				(font
					(size 1.27 1.27)
				)
			)
		)
		(duplicate_pad_numbers_are_jumpers no)
		(fp_line
			(start -0.7874 0.4064)
			(end -0.7874 -0.4064)
			(stroke
				(width 0.1524)
				(type default)
			)
			(layer "F.SilkS")
		)
		(fp_line
			(start 0.7874 0.4064)
			(end -0.7874 0.4064)
			(stroke
				(width 0.1524)
				(type default)
			)
			(layer "F.SilkS")
		)
		(fp_line
			(start -0.7874 -0.4064)
			(end 0.7874 -0.4064)
			(stroke
				(width 0.1524)
				(type default)
			)
			(layer "F.SilkS")
		)
		(fp_line
			(start 0.7874 -0.4064)
			(end 0.7874 0.4064)
			(stroke
				(width 0.1524)
				(type default)
			)
			(layer "F.SilkS")
		)
		(fp_line
			(start -0.67945 0.3048)
			(end -0.67945 -0.305054)
			(stroke
				(width 0.1)
				(type default)
			)
			(layer "F.Fab")
		)
		(fp_line
			(start -0.12065 0.3048)
			(end -0.67945 0.3048)
			(stroke
				(width 0.1)
				(type default)
			)
			(layer "F.Fab")
		)
		(fp_line
			(start 0.120396 0.3048)
			(end 0.120396 0.2794)
			(stroke
				(width 0.1)
				(type default)
			)
			(layer "F.Fab")
		)
		(fp_line
			(start 0.67945 0.3048)
			(end 0.120396 0.3048)
			(stroke
				(width 0.1)
				(type default)
			)
			(layer "F.Fab")
		)
		(fp_line
			(start -0.12065 0.2794)
			(end -0.12065 0.3048)
			(stroke
				(width 0.1)
				(type default)
			)
			(layer "F.Fab")
		)
		(fp_line
			(start 0.120396 0.2794)
			(end -0.12065 0.2794)
			(stroke
				(width 0.1)
				(type default)
			)
			(layer "F.Fab")
		)
		(fp_line
			(start -0.12065 -0.2794)
			(end 0.12065 -0.2794)
			(stroke
				(width 0.1)
				(type default)
			)
			(layer "F.Fab")
		)
		(fp_line
			(start 0.12065 -0.2794)
			(end 0.12065 -0.3048)
			(stroke
				(width 0.1)
				(type default)
			)
			(layer "F.Fab")
		)
		(fp_line
			(start 0.12065 -0.3048)
			(end 0.67945 -0.3048)
			(stroke
				(width 0.1)
				(type default)
			)
			(layer "F.Fab")
		)
		(fp_line
			(start 0.67945 -0.3048)
			(end 0.67945 0.3048)
			(stroke
				(width 0.1)
				(type default)
			)
			(layer "F.Fab")
		)
		(fp_line
			(start -0.67945 -0.305054)
			(end -0.12065 -0.305054)
			(stroke
				(width 0.1)
				(type default)
			)
			(layer "F.Fab")
		)
		(fp_line
			(start -0.12065 -0.305054)
			(end -0.12065 -0.2794)
			(stroke
				(width 0.1)
				(type default)
			)
			(layer "F.Fab")
		)
		(pad "1" smd circle
			(at -0.40005 0 270)
			(size 0 0)
			(layers "F.Cu" "F.Mask" "F.Paste")
			(net "PVCCIN_CPU0")
		)
		(pad "2" smd circle
			(at 0.40005 0 270)
			(size 0 0)
			(layers "F.Cu" "F.Mask" "F.Paste")
			(net "GND")
		)
	)
)
